G04 ================== begin FILE IDENTIFICATION RECORD ==================*
G04 Layout Name:  12433-2a.brd*
G04 Film Name:    TMASK*
G04 File Format:  Gerber RS274X*
G04 File Origin:  Cadence Allegro 16.5-S056*
G04 Origin Date:  Fri Dec 11 16:47:35 2015*
G04 *
G04 Layer:  VIA CLASS/SOLDERMASK_TOP*
G04 Layer:  PIN/SOLDERMASK_TOP*
G04 Layer:  PACKAGE GEOMETRY/SOLDERMASK_TOP*
G04 Layer:  DRAWING FORMAT/LAYER_PCB_STORY*
G04 Layer:  DRAWING FORMAT/LAYER_SOLDER_T*
G04 Layer:  BOARD GEOMETRY/SOLDERMASK_TOP*
G04 *
G04 Offset:    (0.00 0.00)*
G04 Mirror:    No*
G04 Mode:      Positive*
G04 Rotation:  0*
G04 FullContactRelief:  No*
G04 UndefLineWidth:     6.00*
G04 ================== end FILE IDENTIFICATION RECORD ====================*
%FSLAX35Y35*MOIN*%
%IR0*IPPOS*OFA0.00000B0.00000*MIA0B0*SFA1.00000B1.00000*%
%AMMACRO40*
4,1,40,.013,.017,
-.013,.017,
-.013695,.016939,
-.014368,.016759,
-.015,.016464,
-.015571,.016064,
-.016064,.015571,
-.016464,.015,
-.016759,.014368,
-.016939,.013695,
-.017,.013,
-.017,-.013,
-.016939,-.013695,
-.016759,-.014368,
-.016464,-.015,
-.016064,-.015571,
-.015571,-.016064,
-.015,-.016464,
-.014368,-.016759,
-.013695,-.016939,
-.013,-.017,
.013,-.017,
.013695,-.016939,
.014368,-.016759,
.015,-.016464,
.015571,-.016064,
.016064,-.015571,
.016464,-.015,
.016759,-.014368,
.016939,-.013695,
.017,-.013,
.017,.013,
.016939,.013695,
.016759,.014368,
.016464,.015,
.016064,.015571,
.015571,.016064,
.015,.016464,
.014368,.016759,
.013695,.016939,
.013,.017,
0.0*
%
%ADD40MACRO40*%
%AMMACRO31*
4,1,40,.017,-.013,
.017,.013,
.016939,.013695,
.016759,.014368,
.016464,.015,
.016064,.015571,
.015571,.016064,
.015,.016464,
.014368,.016759,
.013695,.016939,
.013,.017,
-.013,.017,
-.013695,.016939,
-.014368,.016759,
-.015,.016464,
-.015571,.016064,
-.016064,.015571,
-.016464,.015,
-.016759,.014368,
-.016939,.013695,
-.017,.013,
-.017,-.013,
-.016939,-.013695,
-.016759,-.014368,
-.016464,-.015,
-.016064,-.015571,
-.015571,-.016064,
-.015,-.016464,
-.014368,-.016759,
-.013695,-.016939,
-.013,-.017,
.013,-.017,
.013695,-.016939,
.014368,-.016759,
.015,-.016464,
.015571,-.016064,
.016064,-.015571,
.016464,-.015,
.016759,-.014368,
.016939,-.013695,
.017,-.013,
0.0*
%
%ADD31MACRO31*%
%ADD33R,.08X.127*%
%ADD55C,.032*%
%ADD15C,.05*%
%ADD51R,.085X.128*%
%ADD23C,.028*%
%ADD56R,.208X.087*%
%ADD13C,.056*%
%ADD48C,.057*%
%ADD39R,.087X.208*%
%AMMACRO82*
4,1,40,-.014,-.008,
-.014,.008,
-.013939,.008695,
-.013759,.009368,
-.013464,.01,
-.013064,.010571,
-.012571,.011064,
-.012,.011464,
-.011368,.011759,
-.010695,.011939,
-.01,.012,
.01,.012,
.010695,.011939,
.011368,.011759,
.012,.011464,
.012571,.011064,
.013064,.010571,
.013464,.01,
.013759,.009368,
.013939,.008695,
.014,.008,
.014,-.008,
.013939,-.008695,
.013759,-.009368,
.013464,-.01,
.013064,-.010571,
.012571,-.011064,
.012,-.011464,
.011368,-.011759,
.010695,-.011939,
.01,-.012,
-.01,-.012,
-.010695,-.011939,
-.011368,-.011759,
-.012,-.011464,
-.012571,-.011064,
-.013064,-.010571,
-.013464,-.01,
-.013759,-.009368,
-.013939,-.008695,
-.014,-.008,
0.0*
%
%ADD82MACRO82*%
%AMMACRO75*
4,1,40,-.007,-.0225,
-.008389,-.022378,
-.009736,-.022018,
-.011,-.021428,
-.012142,-.020628,
-.013128,-.019642,
-.013928,-.0185,
-.014518,-.017236,
-.014878,-.015889,
-.015,-.0145,
-.015,.0145,
-.014878,.015889,
-.014518,.017236,
-.013928,.0185,
-.013128,.019642,
-.012142,.020628,
-.011,.021428,
-.009736,.022018,
-.008389,.022378,
-.007,.0225,
.007,.0225,
.008389,.022378,
.009736,.022018,
.011,.021428,
.012142,.020628,
.013128,.019642,
.013928,.0185,
.014518,.017236,
.014878,.015889,
.015,.0145,
.015,-.0145,
.014878,-.015889,
.014518,-.017236,
.013928,-.0185,
.013128,-.019642,
.012142,-.020628,
.011,-.021428,
.009736,-.022018,
.008389,-.022378,
.007,-.0225,
-.007,-.0225,
0.0*
%
%ADD75MACRO75*%
%ADD47C,.099*%
%AMMACRO41*
4,1,40,.011,-.007,
.011,.007,
.010939,.007695,
.010759,.008368,
.010464,.009,
.010064,.009571,
.009571,.010064,
.009,.010464,
.008368,.010759,
.007695,.010939,
.007,.011,
-.007,.011,
-.007695,.010939,
-.008368,.010759,
-.009,.010464,
-.009571,.010064,
-.010064,.009571,
-.010464,.009,
-.010759,.008368,
-.010939,.007695,
-.011,.007,
-.011,-.007,
-.010939,-.007695,
-.010759,-.008368,
-.010464,-.009,
-.010064,-.009571,
-.009571,-.010064,
-.009,-.010464,
-.008368,-.010759,
-.007695,-.010939,
-.007,-.011,
.007,-.011,
.007695,-.010939,
.008368,-.010759,
.009,-.010464,
.009571,-.010064,
.010064,-.009571,
.010464,-.009,
.010759,-.008368,
.010939,-.007695,
.011,-.007,
0.0*
%
%ADD41MACRO41*%
%AMMACRO18*
4,1,40,.007,.011,
-.007,.011,
-.007695,.010939,
-.008368,.010759,
-.009,.010464,
-.009571,.010064,
-.010064,.009571,
-.010464,.009,
-.010759,.008368,
-.010939,.007695,
-.011,.007,
-.011,-.007,
-.010939,-.007695,
-.010759,-.008368,
-.010464,-.009,
-.010064,-.009571,
-.009571,-.010064,
-.009,-.010464,
-.008368,-.010759,
-.007695,-.010939,
-.007,-.011,
.007,-.011,
.007695,-.010939,
.008368,-.010759,
.009,-.010464,
.009571,-.010064,
.010064,-.009571,
.010464,-.009,
.010759,-.008368,
.010939,-.007695,
.011,-.007,
.011,.007,
.010939,.007695,
.010759,.008368,
.010464,.009,
.010064,.009571,
.009571,.010064,
.009,.010464,
.008368,.010759,
.007695,.010939,
.007,.011,
0.0*
%
%ADD18MACRO18*%
%AMMACRO67*
4,1,40,-.012,.008,
-.012,-.008,
-.011939,-.008695,
-.011759,-.009368,
-.011464,-.01,
-.011064,-.010571,
-.010571,-.011064,
-.01,-.011464,
-.009368,-.011759,
-.008695,-.011939,
-.008,-.012,
.008,-.012,
.008695,-.011939,
.009368,-.011759,
.01,-.011464,
.010571,-.011064,
.011064,-.010571,
.011464,-.01,
.011759,-.009368,
.011939,-.008695,
.012,-.008,
.012,.008,
.011939,.008695,
.011759,.009368,
.011464,.01,
.011064,.010571,
.010571,.011064,
.01,.011464,
.009368,.011759,
.008695,.011939,
.008,.012,
-.008,.012,
-.008695,.011939,
-.009368,.011759,
-.01,.011464,
-.010571,.011064,
-.011064,.010571,
-.011464,.01,
-.011759,.009368,
-.011939,.008695,
-.012,.008,
0.0*
%
%ADD67MACRO67*%
%AMMACRO44*
4,1,40,.008,.012,
-.008,.012,
-.008695,.011939,
-.009368,.011759,
-.01,.011464,
-.010571,.011064,
-.011064,.010571,
-.011464,.01,
-.011759,.009368,
-.011939,.008695,
-.012,.008,
-.012,-.008,
-.011939,-.008695,
-.011759,-.009368,
-.011464,-.01,
-.011064,-.010571,
-.010571,-.011064,
-.01,-.011464,
-.009368,-.011759,
-.008695,-.011939,
-.008,-.012,
.008,-.012,
.008695,-.011939,
.009368,-.011759,
.01,-.011464,
.010571,-.011064,
.011064,-.010571,
.011464,-.01,
.011759,-.009368,
.011939,-.008695,
.012,-.008,
.012,.008,
.011939,.008695,
.011759,.009368,
.011464,.01,
.011064,.010571,
.010571,.011064,
.01,.011464,
.009368,.011759,
.008695,.011939,
.008,.012,
0.0*
%
%ADD44MACRO44*%
%AMMACRO35*
4,1,40,-.013,-.017,
.013,-.017,
.013695,-.016939,
.014368,-.016759,
.015,-.016464,
.015571,-.016064,
.016064,-.015571,
.016464,-.015,
.016759,-.014368,
.016939,-.013695,
.017,-.013,
.017,.013,
.016939,.013695,
.016759,.014368,
.016464,.015,
.016064,.015571,
.015571,.016064,
.015,.016464,
.014368,.016759,
.013695,.016939,
.013,.017,
-.013,.017,
-.013695,.016939,
-.014368,.016759,
-.015,.016464,
-.015571,.016064,
-.016064,.015571,
-.016464,.015,
-.016759,.014368,
-.016939,.013695,
-.017,.013,
-.017,-.013,
-.016939,-.013695,
-.016759,-.014368,
-.016464,-.015,
-.016064,-.015571,
-.015571,-.016064,
-.015,-.016464,
-.014368,-.016759,
-.013695,-.016939,
-.013,-.017,
0.0*
%
%ADD35MACRO35*%
%AMMACRO49*
4,1,40,-.017,.013,
-.017,-.013,
-.016939,-.013695,
-.016759,-.014368,
-.016464,-.015,
-.016064,-.015571,
-.015571,-.016064,
-.015,-.016464,
-.014368,-.016759,
-.013695,-.016939,
-.013,-.017,
.013,-.017,
.013695,-.016939,
.014368,-.016759,
.015,-.016464,
.015571,-.016064,
.016064,-.015571,
.016464,-.015,
.016759,-.014368,
.016939,-.013695,
.017,-.013,
.017,.013,
.016939,.013695,
.016759,.014368,
.016464,.015,
.016064,.015571,
.015571,.016064,
.015,.016464,
.014368,.016759,
.013695,.016939,
.013,.017,
-.013,.017,
-.013695,.016939,
-.014368,.016759,
-.015,.016464,
-.015571,.016064,
-.016064,.015571,
-.016464,.015,
-.016759,.014368,
-.016939,.013695,
-.017,.013,
0.0*
%
%ADD49MACRO49*%
%AMMACRO79*
4,1,25,-.26969,-.01299,
-.26969,-.83465,
.26969,-.83465,
.26969,.83465,
-.26969,.83465,
-.26969,.12087,
-.22638,.12087,
-.214758,.119853,
-.203489,.116834,
-.192915,.111903,
-.183358,.105211,
-.175109,.096962,
-.168417,.087405,
-.163486,.076831,
-.160467,.065562,
-.15945,.05394,
-.160467,.042318,
-.163486,.031049,
-.168417,.020475,
-.175109,.010918,
-.183358,.002669,
-.192915,-.004023,
-.203489,-.008954,
-.214758,-.011973,
-.22638,-.01299,
-.26969,-.01299,
0.0*
%
%ADD79MACRO79*%
%AMMACRO42*
4,1,40,.011,-.007,
.011,.007,
.010939,.007695,
.010759,.008368,
.010464,.009,
.010064,.009571,
.009571,.010064,
.009,.010464,
.008368,.010759,
.007695,.010939,
.007,.011,
-.007,.011,
-.007695,.010939,
-.008368,.010759,
-.009,.010464,
-.009571,.010064,
-.010064,.009571,
-.010464,.009,
-.010759,.008368,
-.010939,.007695,
-.011,.007,
-.011,-.007,
-.010939,-.007695,
-.010759,-.008368,
-.010464,-.009,
-.010064,-.009571,
-.009571,-.010064,
-.009,-.010464,
-.008368,-.010759,
-.007695,-.010939,
-.007,-.011,
.007,-.011,
.007695,-.010939,
.008368,-.010759,
.009,-.010464,
.009571,-.010064,
.010064,-.009571,
.010464,-.009,
.010759,-.008368,
.010939,-.007695,
.011,-.007,
0.0*
%
%ADD42MACRO42*%
%AMMACRO26*
4,1,40,.007,.011,
-.007,.011,
-.007695,.010939,
-.008368,.010759,
-.009,.010464,
-.009571,.010064,
-.010064,.009571,
-.010464,.009,
-.010759,.008368,
-.010939,.007695,
-.011,.007,
-.011,-.007,
-.010939,-.007695,
-.010759,-.008368,
-.010464,-.009,
-.010064,-.009571,
-.009571,-.010064,
-.009,-.010464,
-.008368,-.010759,
-.007695,-.010939,
-.007,-.011,
.007,-.011,
.007695,-.010939,
.008368,-.010759,
.009,-.010464,
.009571,-.010064,
.010064,-.009571,
.010464,-.009,
.010759,-.008368,
.010939,-.007695,
.011,-.007,
.011,.007,
.010939,.007695,
.010759,.008368,
.010464,.009,
.010064,.009571,
.009571,.010064,
.009,.010464,
.008368,.010759,
.007695,.010939,
.007,.011,
0.0*
%
%ADD26MACRO26*%
%AMMACRO66*
4,1,40,-.012,.008,
-.012,-.008,
-.011939,-.008695,
-.011759,-.009368,
-.011464,-.01,
-.011064,-.010571,
-.010571,-.011064,
-.01,-.011464,
-.009368,-.011759,
-.008695,-.011939,
-.008,-.012,
.008,-.012,
.008695,-.011939,
.009368,-.011759,
.01,-.011464,
.010571,-.011064,
.011064,-.010571,
.011464,-.01,
.011759,-.009368,
.011939,-.008695,
.012,-.008,
.012,.008,
.011939,.008695,
.011759,.009368,
.011464,.01,
.011064,.010571,
.010571,.011064,
.01,.011464,
.009368,.011759,
.008695,.011939,
.008,.012,
-.008,.012,
-.008695,.011939,
-.009368,.011759,
-.01,.011464,
-.010571,.011064,
-.011064,.010571,
-.011464,.01,
-.011759,.009368,
-.011939,.008695,
-.012,.008,
0.0*
%
%ADD66MACRO66*%
%AMMACRO43*
4,1,40,.008,.012,
-.008,.012,
-.008695,.011939,
-.009368,.011759,
-.01,.011464,
-.010571,.011064,
-.011064,.010571,
-.011464,.01,
-.011759,.009368,
-.011939,.008695,
-.012,.008,
-.012,-.008,
-.011939,-.008695,
-.011759,-.009368,
-.011464,-.01,
-.011064,-.010571,
-.010571,-.011064,
-.01,-.011464,
-.009368,-.011759,
-.008695,-.011939,
-.008,-.012,
.008,-.012,
.008695,-.011939,
.009368,-.011759,
.01,-.011464,
.010571,-.011064,
.011064,-.010571,
.011464,-.01,
.011759,-.009368,
.011939,-.008695,
.012,-.008,
.012,.008,
.011939,.008695,
.011759,.009368,
.011464,.01,
.011064,.010571,
.010571,.011064,
.01,.011464,
.009368,.011759,
.008695,.011939,
.008,.012,
0.0*
%
%ADD43MACRO43*%
%AMMACRO36*
4,1,40,-.013,-.017,
.013,-.017,
.013695,-.016939,
.014368,-.016759,
.015,-.016464,
.015571,-.016064,
.016064,-.015571,
.016464,-.015,
.016759,-.014368,
.016939,-.013695,
.017,-.013,
.017,.013,
.016939,.013695,
.016759,.014368,
.016464,.015,
.016064,.015571,
.015571,.016064,
.015,.016464,
.014368,.016759,
.013695,.016939,
.013,.017,
-.013,.017,
-.013695,.016939,
-.014368,.016759,
-.015,.016464,
-.015571,.016064,
-.016064,.015571,
-.016464,.015,
-.016759,.014368,
-.016939,.013695,
-.017,.013,
-.017,-.013,
-.016939,-.013695,
-.016759,-.014368,
-.016464,-.015,
-.016064,-.015571,
-.015571,-.016064,
-.015,-.016464,
-.014368,-.016759,
-.013695,-.016939,
-.013,-.017,
0.0*
%
%ADD36MACRO36*%
%AMMACRO50*
4,1,40,-.017,.013,
-.017,-.013,
-.016939,-.013695,
-.016759,-.014368,
-.016464,-.015,
-.016064,-.015571,
-.015571,-.016064,
-.015,-.016464,
-.014368,-.016759,
-.013695,-.016939,
-.013,-.017,
.013,-.017,
.013695,-.016939,
.014368,-.016759,
.015,-.016464,
.015571,-.016064,
.016064,-.015571,
.016464,-.015,
.016759,-.014368,
.016939,-.013695,
.017,-.013,
.017,.013,
.016939,.013695,
.016759,.014368,
.016464,.015,
.016064,.015571,
.015571,.016064,
.015,.016464,
.014368,.016759,
.013695,.016939,
.013,.017,
-.013,.017,
-.013695,.016939,
-.014368,.016759,
-.015,.016464,
-.015571,.016064,
-.016064,.015571,
-.016464,.015,
-.016759,.014368,
-.016939,.013695,
-.017,.013,
0.0*
%
%ADD50MACRO50*%
%ADD53R,.135X.101*%
%ADD85R,.022X.04*%
%ADD60R,.04X.023*%
%ADD69R,.06X.012*%
%ADD54R,.012X.06*%
%ADD74R,.04X.016*%
%ADD73R,.014X.06*%
%ADD32R,.045X.03*%
%ADD22R,.03X.045*%
%ADD83R,.03X.046*%
%ADD52R,.03X.064*%
%ADD10C,.14*%
%ADD77R,.045X.016*%
%ADD76R,.016X.045*%
%ADD72R,.08X.071*%
%ADD45C,.115*%
%ADD16R,.05X.065*%
%ADD12C,.142*%
%ADD58R,.065X.05*%
%ADD81R,.071X.063*%
%ADD71R,.065X.025*%
%ADD46C,.126*%
%ADD34R,.055X.035*%
%ADD14C,.315*%
%ADD80R,.12X.12*%
%ADD64R,.09X.045*%
%ADD62R,.045X.055*%
%ADD61R,.035X.055*%
%ADD29R,.048X.016*%
%ADD70R,.055X.045*%
%ADD57R,.016X.048*%
%ADD78R,.122X.122*%
%ADD25R,.09X.095*%
%ADD11R,.16X.16*%
%AMMACRO84*
4,1,40,.007,.0225,
.008389,.022378,
.009736,.022018,
.011,.021428,
.012142,.020628,
.013128,.019642,
.013928,.0185,
.014518,.017236,
.014878,.015889,
.015,.0145,
.015,-.0145,
.014878,-.015889,
.014518,-.017236,
.013928,-.0185,
.013128,-.019642,
.012142,-.020628,
.011,-.021428,
.009736,-.022018,
.008389,-.022378,
.007,-.0225,
-.007,-.0225,
-.008389,-.022378,
-.009736,-.022018,
-.011,-.021428,
-.012142,-.020628,
-.013128,-.019642,
-.013928,-.0185,
-.014518,-.017236,
-.014878,-.015889,
-.015,-.0145,
-.015,.0145,
-.014878,.015889,
-.014518,.017236,
-.013928,.0185,
-.013128,.019642,
-.012142,.020628,
-.011,.021428,
-.009736,.022018,
-.008389,.022378,
-.007,.0225,
.007,.0225,
0.0*
%
%ADD84MACRO84*%
%ADD68C,.375*%
%ADD63R,.095X.09*%
%ADD59R,.059X.089*%
%AMMACRO38*
4,1,40,.012,-.008,
.012,.008,
.011939,.008695,
.011759,.009368,
.011464,.01,
.011064,.010571,
.010571,.011064,
.01,.011464,
.009368,.011759,
.008695,.011939,
.008,.012,
-.008,.012,
-.008695,.011939,
-.009368,.011759,
-.01,.011464,
-.010571,.011064,
-.011064,.010571,
-.011464,.01,
-.011759,.009368,
-.011939,.008695,
-.012,.008,
-.012,-.008,
-.011939,-.008695,
-.011759,-.009368,
-.011464,-.01,
-.011064,-.010571,
-.010571,-.011064,
-.01,-.011464,
-.009368,-.011759,
-.008695,-.011939,
-.008,-.012,
.008,-.012,
.008695,-.011939,
.009368,-.011759,
.01,-.011464,
.010571,-.011064,
.011064,-.010571,
.011464,-.01,
.011759,-.009368,
.011939,-.008695,
.012,-.008,
0.0*
%
%ADD38MACRO38*%
%AMMACRO28*
4,1,40,-.008,-.012,
.008,-.012,
.008695,-.011939,
.009368,-.011759,
.01,-.011464,
.010571,-.011064,
.011064,-.010571,
.011464,-.01,
.011759,-.009368,
.011939,-.008695,
.012,-.008,
.012,.008,
.011939,.008695,
.011759,.009368,
.011464,.01,
.011064,.010571,
.010571,.011064,
.01,.011464,
.009368,.011759,
.008695,.011939,
.008,.012,
-.008,.012,
-.008695,.011939,
-.009368,.011759,
-.01,.011464,
-.010571,.011064,
-.011064,.010571,
-.011464,.01,
-.011759,.009368,
-.011939,.008695,
-.012,.008,
-.012,-.008,
-.011939,-.008695,
-.011759,-.009368,
-.011464,-.01,
-.011064,-.010571,
-.010571,-.011064,
-.01,-.011464,
-.009368,-.011759,
-.008695,-.011939,
-.008,-.012,
0.0*
%
%ADD28MACRO28*%
%AMMACRO24*
4,1,40,-.007,-.011,
.007,-.011,
.007695,-.010939,
.008368,-.010759,
.009,-.010464,
.009571,-.010064,
.010064,-.009571,
.010464,-.009,
.010759,-.008368,
.010939,-.007695,
.011,-.007,
.011,.007,
.010939,.007695,
.010759,.008368,
.010464,.009,
.010064,.009571,
.009571,.010064,
.009,.010464,
.008368,.010759,
.007695,.010939,
.007,.011,
-.007,.011,
-.007695,.010939,
-.008368,.010759,
-.009,.010464,
-.009571,.010064,
-.010064,.009571,
-.010464,.009,
-.010759,.008368,
-.010939,.007695,
-.011,.007,
-.011,-.007,
-.010939,-.007695,
-.010759,-.008368,
-.010464,-.009,
-.010064,-.009571,
-.009571,-.010064,
-.009,-.010464,
-.008368,-.010759,
-.007695,-.010939,
-.007,-.011,
0.0*
%
%ADD24MACRO24*%
%AMMACRO19*
4,1,40,-.011,.007,
-.011,-.007,
-.010939,-.007695,
-.010759,-.008368,
-.010464,-.009,
-.010064,-.009571,
-.009571,-.010064,
-.009,-.010464,
-.008368,-.010759,
-.007695,-.010939,
-.007,-.011,
.007,-.011,
.007695,-.010939,
.008368,-.010759,
.009,-.010464,
.009571,-.010064,
.010064,-.009571,
.010464,-.009,
.010759,-.008368,
.010939,-.007695,
.011,-.007,
.011,.007,
.010939,.007695,
.010759,.008368,
.010464,.009,
.010064,.009571,
.009571,.010064,
.009,.010464,
.008368,.010759,
.007695,.010939,
.007,.011,
-.007,.011,
-.007695,.010939,
-.008368,.010759,
-.009,.010464,
-.009571,.010064,
-.010064,.009571,
-.010464,.009,
-.010759,.008368,
-.010939,.007695,
-.011,.007,
0.0*
%
%ADD19MACRO19*%
%AMMACRO30*
4,1,40,.017,-.013,
.017,.013,
.016939,.013695,
.016759,.014368,
.016464,.015,
.016064,.015571,
.015571,.016064,
.015,.016464,
.014368,.016759,
.013695,.016939,
.013,.017,
-.013,.017,
-.013695,.016939,
-.014368,.016759,
-.015,.016464,
-.015571,.016064,
-.016064,.015571,
-.016464,.015,
-.016759,.014368,
-.016939,.013695,
-.017,.013,
-.017,-.013,
-.016939,-.013695,
-.016759,-.014368,
-.016464,-.015,
-.016064,-.015571,
-.015571,-.016064,
-.015,-.016464,
-.014368,-.016759,
-.013695,-.016939,
-.013,-.017,
.013,-.017,
.013695,-.016939,
.014368,-.016759,
.015,-.016464,
.015571,-.016064,
.016064,-.015571,
.016464,-.015,
.016759,-.014368,
.016939,-.013695,
.017,-.013,
0.0*
%
%ADD30MACRO30*%
%AMMACRO17*
4,1,40,.013,.017,
-.013,.017,
-.013695,.016939,
-.014368,.016759,
-.015,.016464,
-.015571,.016064,
-.016064,.015571,
-.016464,.015,
-.016759,.014368,
-.016939,.013695,
-.017,.013,
-.017,-.013,
-.016939,-.013695,
-.016759,-.014368,
-.016464,-.015,
-.016064,-.015571,
-.015571,-.016064,
-.015,-.016464,
-.014368,-.016759,
-.013695,-.016939,
-.013,-.017,
.013,-.017,
.013695,-.016939,
.014368,-.016759,
.015,-.016464,
.015571,-.016064,
.016064,-.015571,
.016464,-.015,
.016759,-.014368,
.016939,-.013695,
.017,-.013,
.017,.013,
.016939,.013695,
.016759,.014368,
.016464,.015,
.016064,.015571,
.015571,.016064,
.015,.016464,
.014368,.016759,
.013695,.016939,
.013,.017,
0.0*
%
%ADD17MACRO17*%
%AMMACRO65*
4,1,25,.26969,-.01299,
.26969,-.83465,
-.26969,-.83465,
-.26969,.83465,
.26969,.83465,
.26969,.12087,
.22638,.12087,
.214758,.119853,
.203489,.116834,
.192915,.111903,
.183358,.105211,
.175109,.096962,
.168417,.087405,
.163486,.076831,
.160467,.065562,
.15945,.05394,
.160467,.042318,
.163486,.031049,
.168417,.020475,
.175109,.010918,
.183358,.002669,
.192915,-.004023,
.203489,-.008954,
.214758,-.011973,
.22638,-.01299,
.26969,-.01299,
0.0*
%
%ADD65MACRO65*%
%AMMACRO37*
4,1,40,.012,-.008,
.012,.008,
.011939,.008695,
.011759,.009368,
.011464,.01,
.011064,.010571,
.010571,.011064,
.01,.011464,
.009368,.011759,
.008695,.011939,
.008,.012,
-.008,.012,
-.008695,.011939,
-.009368,.011759,
-.01,.011464,
-.010571,.011064,
-.011064,.010571,
-.011464,.01,
-.011759,.009368,
-.011939,.008695,
-.012,.008,
-.012,-.008,
-.011939,-.008695,
-.011759,-.009368,
-.011464,-.01,
-.011064,-.010571,
-.010571,-.011064,
-.01,-.011464,
-.009368,-.011759,
-.008695,-.011939,
-.008,-.012,
.008,-.012,
.008695,-.011939,
.009368,-.011759,
.01,-.011464,
.010571,-.011064,
.011064,-.010571,
.011464,-.01,
.011759,-.009368,
.011939,-.008695,
.012,-.008,
0.0*
%
%ADD37MACRO37*%
%AMMACRO27*
4,1,40,-.008,-.012,
.008,-.012,
.008695,-.011939,
.009368,-.011759,
.01,-.011464,
.010571,-.011064,
.011064,-.010571,
.011464,-.01,
.011759,-.009368,
.011939,-.008695,
.012,-.008,
.012,.008,
.011939,.008695,
.011759,.009368,
.011464,.01,
.011064,.010571,
.010571,.011064,
.01,.011464,
.009368,.011759,
.008695,.011939,
.008,.012,
-.008,.012,
-.008695,.011939,
-.009368,.011759,
-.01,.011464,
-.010571,.011064,
-.011064,.010571,
-.011464,.01,
-.011759,.009368,
-.011939,.008695,
-.012,.008,
-.012,-.008,
-.011939,-.008695,
-.011759,-.009368,
-.011464,-.01,
-.011064,-.010571,
-.010571,-.011064,
-.01,-.011464,
-.009368,-.011759,
-.008695,-.011939,
-.008,-.012,
0.0*
%
%ADD27MACRO27*%
%AMMACRO21*
4,1,40,-.007,-.011,
.007,-.011,
.007695,-.010939,
.008368,-.010759,
.009,-.010464,
.009571,-.010064,
.010064,-.009571,
.010464,-.009,
.010759,-.008368,
.010939,-.007695,
.011,-.007,
.011,.007,
.010939,.007695,
.010759,.008368,
.010464,.009,
.010064,.009571,
.009571,.010064,
.009,.010464,
.008368,.010759,
.007695,.010939,
.007,.011,
-.007,.011,
-.007695,.010939,
-.008368,.010759,
-.009,.010464,
-.009571,.010064,
-.010064,.009571,
-.010464,.009,
-.010759,.008368,
-.010939,.007695,
-.011,.007,
-.011,-.007,
-.010939,-.007695,
-.010759,-.008368,
-.010464,-.009,
-.010064,-.009571,
-.009571,-.010064,
-.009,-.010464,
-.008368,-.010759,
-.007695,-.010939,
-.007,-.011,
0.0*
%
%ADD21MACRO21*%
%AMMACRO20*
4,1,40,-.011,.007,
-.011,-.007,
-.010939,-.007695,
-.010759,-.008368,
-.010464,-.009,
-.010064,-.009571,
-.009571,-.010064,
-.009,-.010464,
-.008368,-.010759,
-.007695,-.010939,
-.007,-.011,
.007,-.011,
.007695,-.010939,
.008368,-.010759,
.009,-.010464,
.009571,-.010064,
.010064,-.009571,
.010464,-.009,
.010759,-.008368,
.010939,-.007695,
.011,-.007,
.011,.007,
.010939,.007695,
.010759,.008368,
.010464,.009,
.010064,.009571,
.009571,.010064,
.009,.010464,
.008368,.010759,
.007695,.010939,
.007,.011,
-.007,.011,
-.007695,.010939,
-.008368,.010759,
-.009,.010464,
-.009571,.010064,
-.010064,.009571,
-.010464,.009,
-.010759,.008368,
-.010939,.007695,
-.011,.007,
0.0*
%
%ADD20MACRO20*%
%ADD86C,.02*%
%ADD87C,.006*%
G75*
%LPD*%
G75*
G36*
G01X77800Y444315D02*
X86350D01*
Y453265D01*
X77800D01*
Y444315D01*
G37*
G36*
G01X66650D02*
X75200D01*
Y453265D01*
X66650D01*
Y444315D01*
G37*
G36*
G01X77800Y455865D02*
X86350D01*
Y464815D01*
X77800D01*
Y455865D01*
G37*
G36*
G01X66650D02*
X75200D01*
Y464815D01*
X66650D01*
Y455865D01*
G37*
G36*
G01X69200Y1579915D02*
X77750D01*
Y1588865D01*
X69200D01*
Y1579915D01*
G37*
G36*
G01X58050D02*
X66600D01*
Y1588865D01*
X58050D01*
Y1579915D01*
G37*
G36*
G01X69200Y1591465D02*
X77750D01*
Y1600415D01*
X69200D01*
Y1591465D01*
G37*
G36*
G01X58050D02*
X66600D01*
Y1600415D01*
X58050D01*
Y1591465D01*
G37*
G36*
G01X105300Y443815D02*
X113850D01*
Y452765D01*
X105300D01*
Y443815D01*
G37*
G36*
G01X94150D02*
X102700D01*
Y452765D01*
X94150D01*
Y443815D01*
G37*
G36*
G01X105300Y455365D02*
X113850D01*
Y464315D01*
X105300D01*
Y455365D01*
G37*
G36*
G01X94150D02*
X102700D01*
Y464315D01*
X94150D01*
Y455365D01*
G37*
G36*
G01X108556Y686015D02*
Y692015D01*
X104356D01*
Y686015D01*
X108556D01*
G37*
G36*
G01Y677815D02*
Y683815D01*
X104356D01*
Y677815D01*
X108556D01*
G37*
G36*
G01X102156Y686015D02*
Y692015D01*
X97956D01*
Y686015D01*
X102156D01*
G37*
G36*
G01Y677815D02*
Y683815D01*
X97956D01*
Y677815D01*
X102156D01*
G37*
G36*
G01X126150Y1579815D02*
X134700D01*
Y1588765D01*
X126150D01*
Y1579815D01*
G37*
G36*
G01Y1591365D02*
X134700D01*
Y1600315D01*
X126150D01*
Y1591365D01*
G37*
G36*
G01X102300Y1579815D02*
X110850D01*
Y1588765D01*
X102300D01*
Y1579815D01*
G37*
G36*
G01X91150D02*
X99700D01*
Y1588765D01*
X91150D01*
Y1579815D01*
G37*
G36*
G01X102300Y1591365D02*
X110850D01*
Y1600315D01*
X102300D01*
Y1591365D01*
G37*
G36*
G01X91150D02*
X99700D01*
Y1600315D01*
X91150D01*
Y1591365D01*
G37*
G36*
G01X149800Y443815D02*
X158350D01*
Y452765D01*
X149800D01*
Y443815D01*
G37*
G36*
G01X138650D02*
X147200D01*
Y452765D01*
X138650D01*
Y443815D01*
G37*
G36*
G01X177800D02*
X186350D01*
Y452765D01*
X177800D01*
Y443815D01*
G37*
G36*
G01X166650D02*
X175200D01*
Y452765D01*
X166650D01*
Y443815D01*
G37*
G36*
G01X149800Y455365D02*
X158350D01*
Y464315D01*
X149800D01*
Y455365D01*
G37*
G36*
G01X138650D02*
X147200D01*
Y464315D01*
X138650D01*
Y455365D01*
G37*
G36*
G01X177800D02*
X186350D01*
Y464315D01*
X177800D01*
Y455365D01*
G37*
G36*
G01X166650D02*
X175200D01*
Y464315D01*
X166650D01*
Y455365D01*
G37*
G36*
G01X171300Y1579815D02*
X179850D01*
Y1588765D01*
X171300D01*
Y1579815D01*
G37*
G36*
G01X160150D02*
X168700D01*
Y1588765D01*
X160150D01*
Y1579815D01*
G37*
G36*
G01X171300Y1591365D02*
X179850D01*
Y1600315D01*
X171300D01*
Y1591365D01*
G37*
G36*
G01X160150D02*
X168700D01*
Y1600315D01*
X160150D01*
Y1591365D01*
G37*
G36*
G01X137300Y1579815D02*
X145850D01*
Y1588765D01*
X137300D01*
Y1579815D01*
G37*
G36*
G01Y1591365D02*
X145850D01*
Y1600315D01*
X137300D01*
Y1591365D01*
G37*
G54D10*
X-222440Y19685D03*
Y1948818D03*
X643700Y19685D03*
Y1948818D03*
G54D20*
X32700Y256900D03*
X19283Y310682D03*
X32900Y1664200D03*
X25900Y1725100D03*
X56600Y195000D03*
X57400Y211300D03*
X56900Y240000D03*
X63000Y267700D03*
X39200Y347200D03*
X81400Y533900D03*
X78400Y591000D03*
X49600Y576900D03*
X61400Y676800D03*
X57400D03*
X64100Y912800D03*
X77002Y1137897D03*
X83500Y1465200D03*
X96100Y533900D03*
X124900Y588604D03*
X120800D03*
X93065Y597471D03*
X97265D03*
X92465Y610371D03*
X95200Y665700D03*
X110900Y884800D03*
X102600D03*
X119300D03*
X122529Y955744D03*
X117529D03*
X112529D03*
X135000Y1411804D03*
X134700Y1404004D03*
X100500Y1423700D03*
X91500D03*
X105000D03*
X107500Y1490200D03*
X170600Y532500D03*
X155600Y532400D03*
X158000Y578600D03*
X170200Y627100D03*
X180365Y645771D03*
X137765Y662071D03*
X154500Y687200D03*
X149500Y711700D03*
X147900Y1003100D03*
X152100Y1003200D03*
X163500Y997700D03*
X159500D03*
X143800Y1003200D03*
X137500Y1443700D03*
G54D11*
X-181139Y20007D03*
X-180444Y1947256D03*
X601704Y21248D03*
X602399Y1948497D03*
G54D21*
X32800Y272300D03*
X29100Y321300D03*
X30100Y1083600D03*
X18600Y1644300D03*
X18400Y1720700D03*
X20200Y1692800D03*
X85800Y71500D03*
X56900Y155300D03*
Y163300D03*
Y179300D03*
Y159300D03*
Y175300D03*
X46500Y213400D03*
X57800Y217000D03*
X56900Y199300D03*
X70800Y431300D03*
X61000Y577200D03*
X78556Y690465D03*
X80700Y686400D03*
X83996Y848500D03*
Y844100D03*
Y852900D03*
X84000Y857200D03*
Y865700D03*
Y861500D03*
X45400Y916400D03*
X68700Y999800D03*
X84300Y1484000D03*
X49400Y1769800D03*
X88303Y61502D03*
X117900Y437500D03*
X125956Y692165D03*
X125856Y688065D03*
Y683665D03*
X112900Y670600D03*
X111900Y1408200D03*
X91300Y1451000D03*
X109700Y1425900D03*
X91300Y1439000D03*
X128800Y1482000D03*
X159900Y545600D03*
X162700Y622700D03*
X152329Y615065D03*
X171800Y701100D03*
X152096Y1419200D03*
Y1415000D03*
X140500Y1458400D03*
X152100Y1423400D03*
X190800Y439500D03*
G54D30*
X24100Y690900D03*
X28900D03*
X74100Y576200D03*
X65635Y693906D03*
X70535D03*
X82000Y708200D03*
X72200Y711000D03*
X67200D03*
X70800Y981400D03*
X64200Y1004100D03*
X81398Y1137753D03*
X92300Y878454D03*
X87500D03*
X94000Y962800D03*
X103500Y979800D03*
X129900Y992500D03*
X140400Y572400D03*
X158535Y609679D03*
G54D12*
X29921Y24803D03*
Y111417D03*
Y458031D03*
Y544646D03*
Y717874D03*
Y804488D03*
X30000Y1164000D03*
X29921Y1250630D03*
Y1423858D03*
Y1510472D03*
Y1857086D03*
Y1943701D03*
G54D22*
X27471Y262553D03*
X19721D03*
X23596Y255053D03*
X24925Y305350D03*
X32675D03*
X28800Y312850D03*
X35375Y1649050D03*
X27625D03*
X31500Y1641550D03*
X27292Y1714868D03*
X19542D03*
X23417Y1707368D03*
X58692Y909868D03*
X50942D03*
X54817Y902368D03*
X78752Y1613297D03*
Y1619703D03*
X131525Y722550D03*
X135400Y730050D03*
X137752Y1613297D03*
Y1619703D03*
X109252Y1613297D03*
Y1619703D03*
X141625Y682250D03*
X149375D03*
X145500Y689750D03*
X139275Y722550D03*
X138694Y1422269D03*
X146444D03*
X148025Y1401454D03*
X155775D03*
X151900Y1408954D03*
X165494Y1437469D03*
X173244D03*
X169369Y1444969D03*
X142569Y1429769D03*
X165252Y1613297D03*
Y1619703D03*
G54D13*
X15906Y48110D03*
Y58110D03*
Y68110D03*
Y78110D03*
Y88110D03*
Y481339D03*
Y491339D03*
Y501339D03*
Y511339D03*
Y521339D03*
Y741181D03*
Y751181D03*
Y761181D03*
Y771181D03*
Y781181D03*
Y1187323D03*
Y1197323D03*
Y1207323D03*
Y1217323D03*
Y1227323D03*
Y1447165D03*
Y1457165D03*
Y1467165D03*
Y1477165D03*
Y1487165D03*
Y1880394D03*
Y1890394D03*
Y1900394D03*
Y1910394D03*
Y1920394D03*
X138937Y1778819D03*
X128937D03*
X118937D03*
X165000Y1370500D03*
Y1390500D03*
Y1380500D03*
G54D31*
X24100Y685300D03*
X28900D03*
X74100Y570600D03*
X82000Y702600D03*
X65635Y688306D03*
X70535D03*
X72200Y705400D03*
X67200D03*
X70800Y975800D03*
X64200Y998500D03*
X81398Y1132153D03*
X92300Y872854D03*
X87500D03*
X94000Y957200D03*
X103500Y974200D03*
X129900Y986900D03*
X140400Y566800D03*
X158535Y604079D03*
G54D40*
X83847Y61398D03*
X40000Y294300D03*
X56200Y252800D03*
X73500Y591000D03*
X76600Y986600D03*
X67600Y1025000D03*
X116900Y380100D03*
X91529Y533679D03*
X107100Y986000D03*
Y990800D03*
X94800Y1455500D03*
X106800Y1474500D03*
X165900Y532100D03*
X165700Y553300D03*
X182021Y613535D03*
X160300Y1462500D03*
G54D14*
X27559Y157480D03*
Y629921D03*
X17716Y1338583D03*
X27559Y1811023D03*
X179134Y78740D03*
X179133Y570866D03*
X179134Y1161417D03*
Y1889764D03*
G54D32*
X31868Y1089208D03*
Y1096958D03*
X24368Y1093083D03*
X112018Y566991D03*
Y574741D03*
X104518Y570866D03*
X112018Y1255968D03*
Y1263718D03*
X104518Y1259843D03*
G54D50*
X47498Y244499D03*
X52200Y244500D03*
X62700Y259800D03*
X45100Y582900D03*
X81500Y733200D03*
X63202Y1133947D03*
X103900Y482200D03*
X96300Y563300D03*
X129065Y678694D03*
X123465D03*
X124900Y728200D03*
X94500Y982300D03*
X130800Y981400D03*
X133500Y1476800D03*
X146700Y482300D03*
X163300Y702100D03*
X144300Y1116900D03*
X149002Y1116947D03*
G54D41*
X67998Y56503D03*
X67398Y71003D03*
X60600Y195000D03*
X61000Y240000D03*
X61600Y211300D03*
X54300Y263300D03*
X58300D03*
X37200Y256900D03*
X62600Y249200D03*
X73700Y543300D03*
X78600Y574500D03*
X73900Y558800D03*
X39000Y581300D03*
X77200Y705900D03*
X77000Y730800D03*
X43400Y896100D03*
X81398Y1126103D03*
X63498Y1123803D03*
X63198Y1142003D03*
X48300Y1755700D03*
X136779Y543071D03*
X116800Y588596D03*
X128900D03*
X91300Y573200D03*
X136679Y557171D03*
X129335Y662029D03*
X133535D03*
X104900Y662200D03*
X115600Y660200D03*
X116300Y670600D03*
X119600Y831800D03*
X111200D03*
X102900Y831796D03*
X121671Y939756D03*
X117300Y939700D03*
X110500D03*
X136000Y947800D03*
X131500D03*
X123300Y1001300D03*
X119300D03*
X114800D03*
X99000Y979700D03*
X135000Y1003200D03*
X123000Y1424200D03*
X127500D03*
X95500Y1464200D03*
X118000Y1424200D03*
X95600Y1423700D03*
X137000Y1501700D03*
X133000D03*
X129000D03*
X125000D03*
X121000D03*
X117000D03*
X113000D03*
X109000D03*
X93500Y1479200D03*
X145300Y582200D03*
X153500Y570000D03*
X151335Y635829D03*
X148435Y653329D03*
X144235D03*
X154500Y702700D03*
X167700Y699600D03*
X158500Y702700D03*
X149000Y949200D03*
X153000D03*
X157000D03*
X145000D03*
X140500Y947800D03*
X139100Y1003100D03*
X156631Y1431081D03*
X160831Y1430281D03*
X152331Y1431081D03*
X148500Y1474100D03*
X165400Y1430200D03*
X151000Y1491200D03*
X146500D03*
X142000D03*
X137900Y1491100D03*
G54D23*
X18600Y249100D03*
X27900Y269471D03*
X20010Y302982D03*
X11000Y578000D03*
X27300Y593000D03*
X27100Y578100D03*
X24500Y1102000D03*
X33000Y1575000D03*
X32900Y1656300D03*
X33000Y1718500D03*
X32949Y1709451D03*
X20056Y1774189D03*
X43900Y137200D03*
X36200Y318700D03*
X63200Y385100D03*
X62400Y430600D03*
X62900Y412900D03*
X61700Y421900D03*
X70900Y427200D03*
X66000Y510500D03*
X77400Y536300D03*
X83619Y581742D03*
X82900Y574500D03*
X70400Y565500D03*
X43337Y650145D03*
X49665Y642933D03*
X37000Y605000D03*
X86060Y695200D03*
X86000Y689900D03*
X57200Y667884D03*
X65000Y775000D03*
Y766000D03*
X43100Y866100D03*
X76500Y900500D03*
X65900Y900000D03*
X64100Y904800D03*
X85500Y1009500D03*
X73000Y966000D03*
X66900Y969100D03*
X60000Y966800D03*
X81500Y985900D03*
X51500Y974100D03*
X37200Y1091700D03*
X52100Y1132700D03*
X71000Y1232600D03*
X59500Y1627500D03*
X64400Y1605900D03*
X53300Y1609200D03*
X62300Y1641300D03*
X61500Y1716500D03*
X72500Y1717000D03*
Y1699000D03*
X86500Y1713610D03*
Y1700110D03*
Y1726000D03*
X79000Y1766500D03*
X71500Y1760000D03*
X72500Y1733000D03*
X87000Y1774110D03*
X81000Y1802000D03*
X73000Y1813000D03*
X72500Y1830000D03*
X72000Y1798000D03*
X86500Y1793110D03*
X57000Y1805500D03*
X84000Y1869600D03*
X75500Y1838500D03*
X73000Y1847000D03*
X85100Y1844500D03*
X85700Y1852300D03*
X82000Y1915000D03*
X66000Y1917000D03*
X118500Y442000D03*
X122500Y429000D03*
X125100Y408900D03*
X115000Y486100D03*
X106500Y469500D03*
X115500Y476700D03*
X96900Y541600D03*
X99800Y545600D03*
X120800Y598700D03*
X112018Y584900D03*
X106338Y580496D03*
X118565Y592846D03*
X94545Y601197D03*
X101800Y557400D03*
X135200Y566400D03*
X96500Y567600D03*
X99578Y605771D03*
X93063Y629134D03*
X91463Y623143D03*
X129000Y653600D03*
X122088Y665912D03*
X119300Y656600D03*
X111400Y658500D03*
X125202Y657500D03*
X105500Y732000D03*
X95500Y728000D03*
X117500Y724500D03*
X109000Y809500D03*
X119300Y837000D03*
X92700Y858100D03*
X92400Y848900D03*
X103400Y838300D03*
X98700Y877100D03*
X92800Y865300D03*
X111100Y876700D03*
X108200Y953500D03*
X112984Y946835D03*
X120054Y945600D03*
X130903Y958178D03*
X133500Y953000D03*
X94500Y950500D03*
X110400Y997850D03*
X119080Y992900D03*
X127700Y998400D03*
X87600Y965900D03*
X90542Y987958D03*
X97958Y966958D03*
X103500Y966500D03*
X130900Y1003400D03*
X91500Y1030500D03*
X128500Y1076800D03*
X122862Y1385500D03*
X129000Y1416425D03*
X99500Y1407500D03*
X100000Y1443000D03*
X111833Y1469667D03*
X101000Y1460750D03*
X113024Y1452079D03*
X117122Y1448001D03*
X117195Y1456070D03*
X121338Y1452021D03*
X117024Y1452000D03*
X136100Y1463900D03*
X100200Y1433800D03*
X134400Y1454300D03*
X99700Y1450700D03*
X133000Y1447600D03*
X103000Y1429500D03*
X123000Y1431300D03*
X126975Y1435400D03*
X127300Y1468800D03*
X117500Y1519500D03*
X104333Y1498167D03*
X130180Y1486680D03*
X136500Y1481425D03*
X98000Y1564700D03*
X120500Y1606000D03*
X89500Y1610000D03*
X136500Y1651000D03*
X108500Y1727000D03*
X98500Y1717000D03*
Y1696500D03*
X99000Y1707000D03*
X109500Y1719500D03*
X110000Y1709500D03*
X109500Y1699000D03*
X119500Y1710110D03*
Y1696610D03*
Y1725110D03*
X111500Y1768500D03*
X117500Y1732000D03*
X119500Y1760000D03*
X97500Y1775500D03*
X108268Y1777300D03*
X119500Y1747110D03*
X138000Y1824000D03*
X110500Y1801000D03*
X88500Y1785000D03*
X97500Y1796000D03*
X98000Y1786000D03*
X107768Y1789110D03*
X120000Y1811500D03*
X119500Y1796500D03*
X137000Y1877500D03*
X114000Y1843500D03*
X97000Y1850500D03*
X120500Y1836500D03*
Y1850500D03*
X108500Y1851610D03*
X162612Y438169D03*
X143400Y408200D03*
X144400Y470800D03*
X149000Y522500D03*
X174800Y532200D03*
X151500Y533000D03*
X164200Y541900D03*
X149500Y574600D03*
X145230Y571700D03*
X163100Y604717D03*
X174100Y652900D03*
X176300Y608635D03*
X157200Y620800D03*
X146663Y634051D03*
X148595Y618300D03*
X151335Y640400D03*
X145200Y644600D03*
X153200Y653200D03*
X179017Y620013D03*
X173000Y691000D03*
X142000Y701000D03*
X158500Y695000D03*
X145500Y675000D03*
X167600Y703300D03*
X145000Y711750D03*
X160500Y916500D03*
X139500Y951500D03*
X143100Y1007100D03*
X162000Y1027000D03*
X186000Y1133000D03*
X178500Y1268500D03*
X159774Y1414374D03*
X165500Y1450600D03*
X138000Y1448500D03*
X142400Y1499900D03*
X148500Y1479500D03*
X139000Y1696500D03*
Y1712500D03*
X138500Y1727500D03*
X181500Y1716500D03*
X158500D03*
X167500Y1716000D03*
X182000Y1726000D03*
Y1704000D03*
X168500Y1705000D03*
X158500D03*
X184500Y1696500D03*
X163000Y1697000D03*
X174268Y1697110D03*
X152000D03*
Y1710610D03*
Y1725610D03*
X185000Y1738500D03*
X183600Y1765100D03*
X169000Y1781500D03*
X162500Y1773000D03*
X152500Y1771110D03*
X173268Y1776000D03*
X139000Y1800500D03*
X156500Y1782000D03*
X155500Y1798500D03*
X166500Y1798000D03*
X179000Y1798500D03*
X185500Y1804500D03*
X186000Y1790000D03*
X162000D03*
X172768Y1790110D03*
X152000D03*
X139000Y1851000D03*
X138500Y1839500D03*
X185000Y1852500D03*
X161500D03*
X183100Y1838300D03*
X173000Y1852610D03*
X151500Y1851110D03*
X139861Y1889461D03*
X189928Y435800D03*
X197500Y481500D03*
X189000Y1432000D03*
G54D24*
X32500Y321300D03*
X33500Y1083600D03*
X22000Y1644300D03*
X21800Y1720700D03*
X23600Y1692800D03*
X60300Y155300D03*
Y163300D03*
Y179300D03*
Y159300D03*
Y175300D03*
X49900Y213400D03*
X61200Y217000D03*
X60300Y199300D03*
X36200Y272300D03*
X74200Y431300D03*
X64400Y577200D03*
X81956Y690465D03*
X84100Y686400D03*
X48800Y916400D03*
X72100Y999800D03*
X52800Y1769800D03*
X91703Y61502D03*
X89200Y71500D03*
X121300Y437500D03*
X129356Y692165D03*
X129256Y688065D03*
Y683665D03*
X116300Y670600D03*
X87396Y848500D03*
Y844100D03*
Y852900D03*
X87400Y857200D03*
Y865700D03*
Y861500D03*
X115300Y1408200D03*
X94700Y1451000D03*
X113100Y1425900D03*
X94700Y1439000D03*
X87700Y1484000D03*
X132200Y1482000D03*
X163300Y545600D03*
X166100Y622700D03*
X155729Y615065D03*
X175200Y701100D03*
X155496Y1419200D03*
Y1415000D03*
X143900Y1458400D03*
X155500Y1423400D03*
X194200Y439500D03*
G54D60*
X77400Y980050D03*
Y976300D03*
Y972550D03*
X88000D03*
Y976300D03*
Y980050D03*
G54D42*
X67998Y53103D03*
X67398Y67603D03*
X60600Y191600D03*
X62600Y245800D03*
X61000Y236600D03*
X61600Y207900D03*
X54300Y259900D03*
X58300D03*
X37200Y253500D03*
X73700Y539900D03*
X78600Y571100D03*
X73900Y555400D03*
X39000Y577900D03*
X77200Y702500D03*
X77000Y727400D03*
X43400Y892700D03*
X81398Y1122703D03*
X63498Y1120403D03*
X63198Y1138603D03*
X48300Y1752300D03*
X136779Y539671D03*
X116800Y585196D03*
X128900D03*
X91300Y569800D03*
X136679Y553771D03*
X129335Y658629D03*
X133535D03*
X104900Y658800D03*
X115600Y656800D03*
X116300Y667200D03*
X119600Y828400D03*
X111200D03*
X102900Y828396D03*
X121671Y936356D03*
X117300Y936300D03*
X110500D03*
X136000Y944400D03*
X131500D03*
X123300Y997900D03*
X119300D03*
X114800D03*
X99000Y976300D03*
X135000Y999800D03*
X123000Y1420800D03*
X127500D03*
X118000D03*
X95600Y1420300D03*
X95500Y1460800D03*
X137000Y1498300D03*
X133000D03*
X129000D03*
X125000D03*
X121000D03*
X117000D03*
X113000D03*
X109000D03*
X93500Y1475800D03*
X145300Y578800D03*
X153500Y566600D03*
X151335Y632429D03*
X148435Y649929D03*
X144235D03*
X154500Y699300D03*
X167700Y696200D03*
X158500Y699300D03*
X149000Y945800D03*
X153000D03*
X157000D03*
X145000D03*
X140500Y944400D03*
X139100Y999700D03*
X156631Y1427681D03*
X160831Y1426881D03*
X152331Y1427681D03*
X148500Y1470700D03*
X165400Y1426800D03*
X151000Y1487800D03*
X146500D03*
X142000D03*
X137900Y1487700D03*
G54D51*
X69635Y361900D03*
X110735Y361800D03*
X140465D03*
X99365Y361900D03*
X187565Y1507700D03*
X157835D03*
G54D15*
X31299Y230866D03*
Y220866D03*
Y210866D03*
Y348563D03*
Y338563D03*
Y358563D03*
Y903917D03*
Y923917D03*
Y913917D03*
Y1064587D03*
Y1054587D03*
Y1044587D03*
Y1619941D03*
Y1609941D03*
Y1629941D03*
Y1757638D03*
Y1747638D03*
Y1737638D03*
G54D33*
X32359Y1680500D03*
X60641D03*
G54D25*
X22900Y397800D03*
Y418300D03*
X19100Y667000D03*
X36600Y1551500D03*
X81100Y398500D03*
X47700Y397800D03*
X81100Y419000D03*
X47700Y418300D03*
X43900Y667000D03*
X73600Y798400D03*
X63700Y1090600D03*
X88500D03*
X61400Y1551500D03*
X137900Y88500D03*
X113100D03*
X105900Y398500D03*
Y419000D03*
X98400Y798400D03*
X185300Y397900D03*
X160500D03*
X185200Y356700D03*
X160400D03*
X185400Y376900D03*
X160600D03*
X185300Y418400D03*
X160500D03*
X184900Y1531500D03*
X160100D03*
X185000Y1551600D03*
X160200D03*
G54D70*
X89435Y642629D03*
Y635029D03*
X89500Y1461700D03*
Y1469300D03*
X172100Y549100D03*
Y541500D03*
X152265Y601371D03*
X170100Y607600D03*
Y615200D03*
X152265Y608971D03*
X167000Y1457700D03*
Y1465300D03*
G54D61*
X70202Y1138347D03*
Y1125047D03*
X41600Y1767550D03*
Y1754250D03*
X88502Y1136247D03*
Y1122947D03*
G54D34*
X21350Y1781000D03*
X34650D03*
X77953Y54502D03*
X71650Y584000D03*
X58350D03*
X45050Y593000D03*
X58350D03*
X81850Y715400D03*
X81350Y740400D03*
X60150Y1011800D03*
X73450D03*
X64450Y1032100D03*
X77750D03*
X91253Y54502D03*
X95850Y68500D03*
X109150D03*
X95150Y715400D03*
X94650Y740400D03*
G54D16*
X27900Y246900D03*
X25300Y328500D03*
X36300D03*
X16200Y1657100D03*
X27200D03*
X15800Y1699200D03*
X26800D03*
X38900Y246900D03*
X124696Y1392300D03*
X135696D03*
X106000Y1387500D03*
X117000D03*
X154000D03*
X143000D03*
G54D52*
X69000Y440000D03*
X74000D03*
X79000D03*
X84000D03*
X60400Y1575600D03*
X65400D03*
X70400D03*
X75400D03*
X96500Y439500D03*
X101500D03*
X106500D03*
X111500D03*
X128500Y1575500D03*
X133500D03*
X93500D03*
X98500D03*
X103500D03*
X108500D03*
X141000Y439500D03*
X146000D03*
X151000D03*
X156000D03*
X169000D03*
X174000D03*
X179000D03*
X184000D03*
X162500Y1575500D03*
X167500D03*
X172500D03*
X177500D03*
X138500D03*
X143500D03*
G54D43*
X71802Y56547D03*
X71400Y71754D03*
X75200Y741500D03*
X75700Y719100D03*
X53800Y1013100D03*
X103500Y597500D03*
X146365Y611321D03*
G54D17*
X34400Y294300D03*
X78247Y61398D03*
X50600Y252800D03*
X85929Y533679D03*
X67900Y591000D03*
X71000Y986600D03*
X62000Y1025000D03*
X111300Y380100D03*
X101500Y986000D03*
Y990800D03*
X89200Y1455500D03*
X101200Y1474500D03*
X160300Y532100D03*
X160100Y553300D03*
X176421Y613535D03*
X154700Y1462500D03*
G54D62*
X80200Y1477500D03*
X107600Y558300D03*
X115200D03*
X87800Y1477500D03*
X106770Y1480640D03*
X99170D03*
X183700Y1606500D03*
X180700Y1641000D03*
X188300D03*
X191300Y1606500D03*
G54D80*
X150000Y64500D03*
X152500Y1906000D03*
G54D71*
X93206Y677415D03*
Y682415D03*
Y687415D03*
Y692415D03*
X113306D03*
Y687415D03*
Y682415D03*
Y677415D03*
G54D53*
X72000Y473548D03*
Y491452D03*
X90000Y473548D03*
Y491452D03*
X176000Y473048D03*
Y490952D03*
X158000Y473048D03*
Y490952D03*
G54D26*
X33400Y570800D03*
X27700Y1106000D03*
X22000Y1640200D03*
X34100Y1774400D03*
X23300Y1769600D03*
X70700Y63500D03*
X60300Y171300D03*
Y183300D03*
Y167300D03*
Y187300D03*
X61200Y221000D03*
X49900Y217400D03*
X36082Y264217D03*
X60300Y280000D03*
X81944Y694635D03*
X83400Y682200D03*
X68700Y730000D03*
X72100Y1004300D03*
X63000Y1020600D03*
X75700Y1025400D03*
X75800Y1020900D03*
X41400Y1096000D03*
X72200Y1175100D03*
X38400Y1788200D03*
X102100Y549600D03*
X87100Y569900D03*
X94700Y671000D03*
X119000Y660200D03*
X108300Y662200D03*
X91200Y707900D03*
X89700Y733400D03*
X113100Y1421600D03*
X107500Y1408100D03*
X133200Y1428300D03*
X94700Y1446500D03*
X153500Y430800D03*
X148700Y568000D03*
X156200Y587000D03*
X166100Y626700D03*
X177700Y624300D03*
X151404Y1394000D03*
X143900Y1466400D03*
Y1462400D03*
X143600Y1453300D03*
X160700Y1458000D03*
G54D35*
X33600Y1769900D03*
X81300Y71500D03*
X63800Y662300D03*
Y657600D03*
X54300Y1764700D03*
X115800Y769100D03*
Y764100D03*
X105300Y1058400D03*
Y1053700D03*
X187900Y1652700D03*
Y1648000D03*
X147447Y1878698D03*
X147400Y1883700D03*
G54D44*
X71802Y52947D03*
X71400Y68154D03*
X75200Y737900D03*
X75700Y715500D03*
X53800Y1009500D03*
X103500Y593900D03*
X146365Y607721D03*
G54D27*
X35000Y581300D03*
X58100Y1030800D03*
X87400Y574100D03*
X149500Y578600D03*
X164600Y608500D03*
X150500Y699200D03*
G54D63*
X78900Y1498700D03*
Y1523500D03*
X124298Y1883503D03*
Y1908303D03*
X145798Y1151303D03*
Y1126503D03*
G54D81*
X171370Y634819D03*
X159800D03*
X171370Y645839D03*
X159800D03*
G54D45*
X47244Y68110D03*
Y501338D03*
Y761181D03*
Y1207323D03*
Y1467165D03*
Y1900393D03*
G54D72*
X134709Y710500D03*
X117291D03*
G54D54*
X85400Y544750D03*
X83430D03*
X81465D03*
Y561050D03*
X83430D03*
X85400D03*
X89335Y544750D03*
X87370D03*
Y561050D03*
X89335D03*
X108710Y612629D03*
X110675D03*
X112645D03*
X114615D03*
X116580D03*
X118550D03*
X120520D03*
X122490D03*
X124455D03*
X126425D03*
X128395D03*
X130360D03*
Y646029D03*
X128395D03*
X126425D03*
X124455D03*
X122490D03*
X120520D03*
X118550D03*
X116580D03*
X114615D03*
X112645D03*
X110675D03*
X108710D03*
X153135Y542950D03*
X151170D03*
X149200D03*
X147230D03*
X145265D03*
Y559250D03*
X147230D03*
X149200D03*
X151170D03*
X153135D03*
G54D36*
X28000Y1769900D03*
X75700Y71500D03*
X58200Y662300D03*
Y657600D03*
X48700Y1764700D03*
X110200Y769100D03*
Y764100D03*
X99700Y1058400D03*
Y1053700D03*
X182300Y1652700D03*
Y1648000D03*
X141847Y1878698D03*
X141800Y1883700D03*
G54D18*
X32682Y264217D03*
X30000Y570800D03*
X24300Y1106000D03*
X18600Y1640200D03*
X30700Y1774400D03*
X19900Y1769600D03*
X35000Y1788200D03*
X67300Y63500D03*
X56900Y171300D03*
Y183300D03*
Y167300D03*
Y187300D03*
X57800Y221000D03*
X46500Y217400D03*
X56900Y280000D03*
X83700Y569900D03*
X78544Y694635D03*
X80000Y682200D03*
X86300Y733400D03*
X65300Y730000D03*
X68700Y1004300D03*
X59600Y1020600D03*
X72300Y1025400D03*
X72400Y1020900D03*
X38000Y1096000D03*
X68800Y1175100D03*
X98700Y549600D03*
X91300Y671000D03*
X115600Y660200D03*
X104900Y662200D03*
X87800Y707900D03*
X109700Y1421600D03*
X104100Y1408100D03*
X129800Y1428300D03*
X91300Y1446500D03*
X150100Y430800D03*
X145300Y568000D03*
X152800Y587000D03*
X162700Y626700D03*
X174300Y624300D03*
X148004Y1394000D03*
X140500Y1466400D03*
Y1462400D03*
X140200Y1453300D03*
X157300Y1458000D03*
G54D37*
X30300Y1787800D03*
X64500Y573000D03*
X81900Y966200D03*
X71200Y1144500D03*
X87000Y1143000D03*
X94800Y1431500D03*
Y1434900D03*
X133300Y1432000D03*
X94800Y1442800D03*
X163400Y549300D03*
X144300Y695500D03*
G54D19*
X32700Y253500D03*
X19283Y307282D03*
X32900Y1660800D03*
X25900Y1721700D03*
X56600Y191600D03*
X57400Y207900D03*
X56900Y236600D03*
X63000Y264300D03*
X39200Y343800D03*
X81400Y530500D03*
X78400Y587600D03*
X49600Y573500D03*
X61400Y673400D03*
X57400D03*
X64100Y909400D03*
X77002Y1134497D03*
X83500Y1461800D03*
X96100Y530500D03*
X124900Y585204D03*
X120800D03*
X93065Y594071D03*
X97265D03*
X92465Y606971D03*
X95200Y662300D03*
X110900Y881400D03*
X102600D03*
X119300D03*
X122529Y952344D03*
X117529D03*
X112529D03*
X100500Y1420300D03*
X91500D03*
X105000D03*
X135000Y1408404D03*
X134700Y1400604D03*
X107500Y1486800D03*
X170600Y529100D03*
X155600Y529000D03*
X158000Y575200D03*
X170200Y623700D03*
X180365Y642371D03*
X137765Y658671D03*
X154500Y683800D03*
X149500Y708300D03*
X147900Y999700D03*
X152100Y999800D03*
X163500Y994300D03*
X159500D03*
X143800Y999800D03*
X137500Y1440300D03*
G54D28*
X35000Y584900D03*
X58100Y1034400D03*
X87400Y577700D03*
X149500Y582200D03*
X164600Y612100D03*
X150500Y702800D03*
G54D64*
X71250Y1613297D03*
Y1619703D03*
X130250Y1613297D03*
Y1619703D03*
X101750Y1613297D03*
Y1619703D03*
X157750Y1613297D03*
Y1619703D03*
G54D46*
X80709Y119409D03*
Y329409D03*
X149606Y119409D03*
Y329409D03*
G54D73*
X116175Y846304D03*
X113620D03*
X111060D03*
X108500D03*
X105940D03*
X103380D03*
X100825D03*
Y868504D03*
X103380D03*
X105940D03*
X108500D03*
X111060D03*
X113620D03*
X116175D03*
X121640Y963000D03*
X119080D03*
X116520D03*
X113960D03*
Y985200D03*
X116520D03*
X119080D03*
X121640D03*
X155825Y732304D03*
X158380D03*
X160940D03*
X163500D03*
X166060D03*
X168620D03*
X171175D03*
Y710104D03*
X168620D03*
X166060D03*
X163500D03*
X160940D03*
X158380D03*
X155825D03*
X137340Y959500D03*
X139900D03*
X142460D03*
X145020D03*
X147580D03*
X150140D03*
X152700D03*
X155260D03*
Y981700D03*
X152700D03*
X150140D03*
X147580D03*
X145020D03*
X142460D03*
X139900D03*
X137340D03*
G54D82*
X180465Y631371D03*
Y634971D03*
G54D55*
X73900Y550100D03*
X136771Y548521D03*
X132735Y593429D03*
X125835Y593629D03*
X131935Y601929D03*
X105000Y603200D03*
X101900Y654100D03*
X92971Y617335D03*
X117100Y1430100D03*
X144329Y598765D03*
X139929Y604165D03*
X140135Y593229D03*
X160700Y615900D03*
X151029Y627565D03*
X156700Y626800D03*
X179000Y706500D03*
X147600Y994600D03*
X154000Y994500D03*
X142000D03*
G54D65*
X96457Y1773425D03*
G54D38*
X26700Y1787800D03*
X60900Y573000D03*
X78300Y966200D03*
X83400Y1143000D03*
X67600Y1144500D03*
X91200Y1431500D03*
Y1434900D03*
X129700Y1432000D03*
X91200Y1442800D03*
X159800Y549300D03*
X140700Y695500D03*
G54D29*
X36250Y690560D03*
Y688000D03*
Y685440D03*
X51750Y690560D03*
Y688000D03*
Y685440D03*
X58250D03*
Y690560D03*
X42750Y685440D03*
Y690560D03*
G54D83*
X141100Y1401696D03*
Y1410096D03*
X158600Y1446404D03*
Y1438004D03*
G54D74*
X113800Y1397140D03*
Y1399700D03*
Y1402260D03*
X106400D03*
Y1399700D03*
Y1397140D03*
G54D47*
X80709Y139409D03*
Y309409D03*
X149606Y139409D03*
Y309409D03*
G54D56*
X73403Y606702D03*
Y633502D03*
X122097Y1125298D03*
Y1152098D03*
X98497Y1883198D03*
Y1909998D03*
G54D84*
X147500Y1437250D03*
X143625Y1444750D03*
X151375D03*
G54D57*
X66875Y674606D03*
X69435D03*
X71995D03*
Y681106D03*
X66875D03*
G54D66*
X48200Y1760300D03*
X98600Y553300D03*
X86800Y537800D03*
X96100D03*
X112900Y603500D03*
X107600Y593700D03*
X170600Y536400D03*
X160900Y536500D03*
G54D75*
X125000Y1409454D03*
X121125Y1401954D03*
X128875D03*
G54D39*
X72200Y86200D03*
X72602Y757897D03*
X63700Y1050100D03*
X99000Y86200D03*
X99402Y757897D03*
X90500Y1050100D03*
G54D48*
X80709Y161889D03*
Y171889D03*
Y181889D03*
Y191889D03*
Y204409D03*
Y214409D03*
Y224409D03*
Y234409D03*
Y244409D03*
Y256929D03*
Y266929D03*
Y276929D03*
Y286929D03*
X110709Y161889D03*
Y171889D03*
X100709Y161889D03*
Y171889D03*
X90709Y161889D03*
Y171889D03*
X110709Y181889D03*
Y191889D03*
X100709Y181889D03*
Y191889D03*
X90709Y181889D03*
Y191889D03*
X110709Y204409D03*
Y214409D03*
Y224409D03*
Y234409D03*
Y244409D03*
X100709Y204409D03*
Y214409D03*
Y224409D03*
Y234409D03*
Y244409D03*
X90709Y204409D03*
Y214409D03*
Y224409D03*
Y234409D03*
Y244409D03*
X110709Y256929D03*
Y266929D03*
X100709Y256929D03*
Y266929D03*
X90709Y256929D03*
Y266929D03*
X110709Y276929D03*
Y286929D03*
X100709Y276929D03*
Y286929D03*
X90709Y276929D03*
Y286929D03*
X179606Y161889D03*
Y171889D03*
X169606Y161889D03*
Y171889D03*
X159606Y161889D03*
Y171889D03*
X149606Y161889D03*
Y171889D03*
X179606Y181889D03*
Y191889D03*
X169606Y181889D03*
Y191889D03*
X159606Y181889D03*
Y191889D03*
X149606Y181889D03*
Y191889D03*
X179606Y204409D03*
Y214409D03*
Y224409D03*
Y234409D03*
Y244409D03*
X169606Y204409D03*
Y214409D03*
Y224409D03*
Y234409D03*
Y244409D03*
X159606Y204409D03*
Y214409D03*
Y224409D03*
Y234409D03*
Y244409D03*
X149606Y204409D03*
Y214409D03*
Y224409D03*
Y234409D03*
Y244409D03*
X179606Y256929D03*
Y266929D03*
X169606Y256929D03*
Y266929D03*
X159606Y256929D03*
Y266929D03*
X149606Y256929D03*
Y266929D03*
X179606Y276929D03*
Y286929D03*
X169606Y276929D03*
Y286929D03*
X159606Y276929D03*
Y286929D03*
X149606Y276929D03*
Y286929D03*
G54D58*
X49900Y883800D03*
Y894800D03*
X63800Y986600D03*
Y975600D03*
X39000Y1022500D03*
Y1033500D03*
X96000Y931000D03*
Y942000D03*
X147000Y732000D03*
Y721000D03*
G54D76*
X111882Y1461600D03*
X114441D03*
X117000D03*
X119559D03*
X122118D03*
Y1442400D03*
X119559D03*
X117000D03*
X114441D03*
X111882D03*
G54D85*
X142300Y1471800D03*
Y1480800D03*
G54D49*
X47498Y238899D03*
X52200Y238900D03*
X62700Y254200D03*
X45100Y577300D03*
X81500Y727600D03*
X63202Y1128347D03*
X103900Y476600D03*
X96300Y557700D03*
X129065Y673094D03*
X123465D03*
X124900Y722600D03*
X94500Y976700D03*
X130800Y975800D03*
X133500Y1471200D03*
X146700Y476700D03*
X163300Y696500D03*
X144300Y1111300D03*
X149002Y1111347D03*
G54D67*
X51800Y1760300D03*
X102200Y553300D03*
X90400Y537800D03*
X99700D03*
X116500Y603500D03*
X111200Y593700D03*
X174200Y536400D03*
X164500Y536500D03*
G54D86*
G01X-448201Y-66763D02*
X-480201D01*
G01X-448201Y-82763D02*
Y-162763D01*
G01Y-118263D02*
X752899D01*
G01X-448201Y-162763D02*
X752899D01*
G01X-452201Y-66763D02*
G02I-12000J0D01*
G01X-457351D02*
G02I-6850J0D01*
G01X-464201Y-82763D02*
Y-50763D01*
G01X-448201Y-82763D02*
X752899D01*
G01X-34601D02*
Y-162763D01*
G01X102899Y-82763D02*
Y-162763D01*
G01X217899Y-82763D02*
Y-162763D01*
G01X385399Y-82763D02*
Y-162763D01*
G01X555399Y-82763D02*
Y-162763D01*
G01X752899Y-82763D02*
Y-162763D01*
G01X780899Y-66763D02*
G02I-12000J0D01*
G01X775749D02*
G02I-6850J0D01*
G01X768899Y-82763D02*
Y-50763D01*
G01X784899Y-66763D02*
X752899D01*
G54D59*
X86699Y949600D03*
X63901D03*
G54D68*
X96457Y1747835D03*
Y1823031D03*
X178937Y1328740D03*
X161417Y1747835D03*
Y1823031D03*
G54D77*
X126600Y1457118D03*
Y1454559D03*
Y1452000D03*
Y1449441D03*
Y1446882D03*
X107400D03*
Y1449441D03*
Y1452000D03*
Y1454559D03*
Y1457118D03*
G54D87*
G01X-430254Y-152763D02*
Y-135263D01*
G01X-421958D02*
X-430254Y-146055D01*
G01X-420648Y-152763D02*
X-426543Y-141097D01*
G01X-412973Y-152763D02*
Y-135263D01*
X-402929Y-152763D01*
Y-135263D01*
G01X-390451Y-152763D02*
X-392198Y-152471D01*
X-393726Y-151305D01*
X-395036Y-149555D01*
X-395910Y-147513D01*
X-396346Y-145180D01*
Y-142846D01*
X-395910Y-140513D01*
X-395036Y-138471D01*
X-393726Y-136722D01*
X-392198Y-135555D01*
X-390451Y-135263D01*
X-388705Y-135555D01*
X-387176Y-136722D01*
X-385866Y-138471D01*
X-384992Y-140513D01*
X-384556Y-142846D01*
Y-145180D01*
X-384992Y-147513D01*
X-385866Y-149555D01*
X-387176Y-151305D01*
X-388705Y-152471D01*
X-390451Y-152763D01*
G01X-377536D02*
X-368366Y-135263D01*
G01X-377536D02*
X-368366Y-152763D01*
G01X-362001Y-158596D02*
X-348901D01*
G01X-342099Y-152763D02*
Y-135263D01*
X-333803D01*
G01X-336859Y-143721D02*
X-342099D01*
G01X-325910Y-152763D02*
X-320451Y-135263D01*
X-314992Y-152763D01*
G01X-316958Y-146638D02*
X-323945D01*
G01X-307973Y-152763D02*
Y-135263D01*
X-297929Y-152763D01*
Y-135263D01*
G01X-263148Y-136722D02*
X-264458Y-135846D01*
X-265986Y-135263D01*
X-267733D01*
X-269698Y-136138D01*
X-271226Y-137596D01*
X-272318Y-139347D01*
X-273191Y-142263D01*
X-273410Y-144888D01*
X-272973Y-147513D01*
X-272318Y-149263D01*
X-271008Y-151013D01*
X-269479Y-152180D01*
X-267951Y-152763D01*
X-266423D01*
X-264894Y-152180D01*
X-263584Y-151305D01*
X-262492Y-150139D01*
G01X-250451Y-152763D02*
X-252198Y-152471D01*
X-253726Y-151305D01*
X-255036Y-149555D01*
X-255910Y-147513D01*
X-256346Y-145180D01*
Y-142846D01*
X-255910Y-140513D01*
X-255036Y-138471D01*
X-253726Y-136722D01*
X-252198Y-135555D01*
X-250451Y-135263D01*
X-248705Y-135555D01*
X-247176Y-136722D01*
X-245866Y-138471D01*
X-244992Y-140513D01*
X-244556Y-142846D01*
Y-145180D01*
X-244992Y-147513D01*
X-245866Y-149555D01*
X-247176Y-151305D01*
X-248705Y-152471D01*
X-250451Y-152763D01*
G01X-237973D02*
Y-135263D01*
X-227929Y-152763D01*
Y-135263D01*
G01X-215451D02*
Y-152763D01*
G01X-220473Y-135263D02*
X-210429D01*
G01X-202318Y-152763D02*
Y-135263D01*
X-196859D01*
X-195113Y-136138D01*
X-194021Y-137305D01*
X-193584Y-139638D01*
X-194021Y-141972D01*
X-195331Y-143430D01*
X-196859Y-144305D01*
X-202318D01*
G01X-196859D02*
X-193584Y-152763D01*
G01X-180451D02*
X-182198Y-152471D01*
X-183726Y-151305D01*
X-185036Y-149555D01*
X-185910Y-147513D01*
X-186346Y-145180D01*
Y-142846D01*
X-185910Y-140513D01*
X-185036Y-138471D01*
X-183726Y-136722D01*
X-182198Y-135555D01*
X-180451Y-135263D01*
X-178705Y-135555D01*
X-177176Y-136722D01*
X-175866Y-138471D01*
X-174992Y-140513D01*
X-174556Y-142846D01*
Y-145180D01*
X-174992Y-147513D01*
X-175866Y-149555D01*
X-177176Y-151305D01*
X-178705Y-152471D01*
X-180451Y-152763D01*
G01X-167318Y-135263D02*
Y-152763D01*
X-158584D01*
G01X-126205Y-143430D02*
X-125331Y-142555D01*
X-124676Y-141097D01*
X-124239Y-139054D01*
X-124676Y-137305D01*
X-125549Y-136138D01*
X-127078Y-135263D01*
X-132973D01*
Y-152763D01*
X-125768D01*
X-124239Y-151597D01*
X-123366Y-149846D01*
X-122929Y-147805D01*
X-123366Y-145763D01*
X-124676Y-144013D01*
X-126205Y-143430D01*
X-132973D01*
G01X-110451Y-152763D02*
X-112198Y-152471D01*
X-113726Y-151305D01*
X-115036Y-149555D01*
X-115910Y-147513D01*
X-116346Y-145180D01*
Y-142846D01*
X-115910Y-140513D01*
X-115036Y-138471D01*
X-113726Y-136722D01*
X-112198Y-135555D01*
X-110451Y-135263D01*
X-108705Y-135555D01*
X-107176Y-136722D01*
X-105866Y-138471D01*
X-104992Y-140513D01*
X-104556Y-142846D01*
Y-145180D01*
X-104992Y-147513D01*
X-105866Y-149555D01*
X-107176Y-151305D01*
X-108705Y-152471D01*
X-110451Y-152763D01*
G01X-98410D02*
X-92951Y-135263D01*
X-87492Y-152763D01*
G01X-89458Y-146638D02*
X-96445D01*
G01X-79818Y-152763D02*
Y-135263D01*
X-74359D01*
X-72613Y-136138D01*
X-71521Y-137305D01*
X-71084Y-139638D01*
X-71521Y-141972D01*
X-72831Y-143430D01*
X-74359Y-144305D01*
X-79818D01*
G01X-74359D02*
X-71084Y-152763D01*
G01X-62754D02*
Y-135263D01*
X-58388D01*
X-56641Y-136138D01*
X-55331Y-137305D01*
X-54239Y-139054D01*
X-53366Y-141097D01*
X-53148Y-144013D01*
X-53366Y-146930D01*
X-54239Y-148972D01*
X-55331Y-150722D01*
X-56641Y-151888D01*
X-58388Y-152763D01*
X-62754D01*
G01X-282378Y-107763D02*
Y-90263D01*
X-276701Y-104846D01*
X-271024Y-90263D01*
Y-107763D01*
G01X-259201D02*
X-260511Y-107471D01*
X-261821Y-106305D01*
X-262695Y-104263D01*
X-263131Y-101930D01*
X-262695Y-99596D01*
X-261821Y-97555D01*
X-260511Y-96388D01*
X-259201Y-96097D01*
X-257891Y-96388D01*
X-256581Y-97555D01*
X-255708Y-99596D01*
X-255489Y-101930D01*
X-255708Y-104263D01*
X-256581Y-106305D01*
X-257891Y-107471D01*
X-259201Y-107763D01*
G01X-237771Y-90263D02*
Y-107763D01*
G01Y-105139D02*
X-238644Y-106597D01*
X-239955Y-107471D01*
X-241483Y-107763D01*
X-243229Y-107180D01*
X-244539Y-105722D01*
X-245413Y-103972D01*
X-245631Y-101930D01*
X-245413Y-99888D01*
X-244539Y-98138D01*
X-243229Y-96680D01*
X-241483Y-96097D01*
X-239955Y-96388D01*
X-238863Y-96972D01*
X-237771Y-98138D01*
G01X-227476Y-99888D02*
X-220489D01*
X-221144Y-97846D01*
X-222236Y-96680D01*
X-223764Y-96097D01*
X-225293Y-96388D01*
X-226603Y-97263D01*
X-227476Y-99305D01*
X-227913Y-101055D01*
Y-102805D01*
X-227476Y-104555D01*
X-226384Y-106305D01*
X-225074Y-107471D01*
X-223546Y-107763D01*
X-222018Y-107180D01*
X-220489Y-105430D01*
G01X-206701Y-107763D02*
Y-90263D01*
G01X-14018Y-107763D02*
Y-90263D01*
X-8778D01*
X-7031Y-91138D01*
X-5721Y-93180D01*
X-5284Y-95513D01*
X-5721Y-97846D01*
X-6813Y-99596D01*
X-8778Y-100472D01*
X-14018D01*
G01X12652Y-91722D02*
X11342Y-90846D01*
X9814Y-90263D01*
X8067D01*
X6102Y-91138D01*
X4574Y-92596D01*
X3482Y-94347D01*
X2609Y-97263D01*
X2390Y-99888D01*
X2827Y-102513D01*
X3482Y-104263D01*
X4792Y-106013D01*
X6321Y-107180D01*
X7849Y-107763D01*
X9377D01*
X10906Y-107180D01*
X12216Y-106305D01*
X13308Y-105139D01*
G01X27095Y-98430D02*
X27969Y-97555D01*
X28624Y-96097D01*
X29061Y-94054D01*
X28624Y-92305D01*
X27751Y-91138D01*
X26222Y-90263D01*
X20327D01*
Y-107763D01*
X27532D01*
X29061Y-106597D01*
X29934Y-104846D01*
X30371Y-102805D01*
X29934Y-100763D01*
X28624Y-99013D01*
X27095Y-98430D01*
X20327D01*
G01X36299Y-113596D02*
X49399D01*
G01X55327Y-107763D02*
Y-90263D01*
X65371Y-107763D01*
Y-90263D01*
G01X77849Y-107763D02*
X76102Y-107471D01*
X74574Y-106305D01*
X73264Y-104555D01*
X72390Y-102513D01*
X71954Y-100180D01*
Y-97846D01*
X72390Y-95513D01*
X73264Y-93471D01*
X74574Y-91722D01*
X76102Y-90555D01*
X77849Y-90263D01*
X79595Y-90555D01*
X81124Y-91722D01*
X82434Y-93471D01*
X83308Y-95513D01*
X83744Y-97846D01*
Y-100180D01*
X83308Y-102513D01*
X82434Y-104555D01*
X81124Y-106305D01*
X79595Y-107471D01*
X77849Y-107763D01*
G01X-901Y-152763D02*
Y-135263D01*
X-3521Y-138763D01*
G01Y-152763D02*
X1719D01*
G01X12451Y-138180D02*
X13761Y-136430D01*
X15289Y-135555D01*
X17036Y-135263D01*
X19219Y-135846D01*
X20747Y-137305D01*
X21184Y-139054D01*
X20966Y-140805D01*
X20092Y-142263D01*
X15726Y-145180D01*
X13761Y-147221D01*
X12451Y-150139D01*
X12014Y-152763D01*
X21184D01*
G01X36719D02*
Y-135263D01*
X28640Y-147805D01*
X39558D01*
G01X46796Y-149263D02*
X48105Y-151305D01*
X49852Y-152471D01*
X51817Y-152763D01*
X53564Y-152471D01*
X55311Y-151013D01*
X56402Y-149263D01*
X56621Y-147513D01*
X56184Y-145472D01*
X54656Y-144013D01*
X53127Y-143430D01*
X51162D01*
G01X53127D02*
X54437Y-142555D01*
X55529Y-141097D01*
X55966Y-139347D01*
X55529Y-137596D01*
X54437Y-136138D01*
X52472Y-135263D01*
X50507Y-135555D01*
X48542Y-136722D01*
G01X64296Y-149263D02*
X65605Y-151305D01*
X67352Y-152471D01*
X69317Y-152763D01*
X71064Y-152471D01*
X72811Y-151013D01*
X73902Y-149263D01*
X74121Y-147513D01*
X73684Y-145472D01*
X72156Y-144013D01*
X70627Y-143430D01*
X68662D01*
G01X70627D02*
X71937Y-142555D01*
X73029Y-141097D01*
X73466Y-139347D01*
X73029Y-137596D01*
X71937Y-136138D01*
X69972Y-135263D01*
X68007Y-135555D01*
X66042Y-136722D01*
G01X128690Y-90263D02*
X134149Y-107763D01*
X139608Y-90263D01*
G01X156016Y-107763D02*
X147282D01*
Y-90263D01*
X156016D01*
G01X152522Y-98721D02*
X147282D01*
G01X164782Y-107763D02*
Y-90263D01*
X170241D01*
X171987Y-91138D01*
X173079Y-92305D01*
X173516Y-94638D01*
X173079Y-96972D01*
X171769Y-98430D01*
X170241Y-99305D01*
X164782D01*
G01X170241D02*
X173516Y-107763D01*
G01X186649Y-108346D02*
X186212Y-108055D01*
Y-107471D01*
X186649Y-107180D01*
X187086Y-107471D01*
Y-108055D01*
X186649Y-108346D01*
G01X147501Y-138180D02*
X148811Y-136430D01*
X150339Y-135555D01*
X152086Y-135263D01*
X154269Y-135846D01*
X155797Y-137305D01*
X156234Y-139054D01*
X156016Y-140805D01*
X155142Y-142263D01*
X150776Y-145180D01*
X148811Y-147221D01*
X147501Y-150139D01*
X147064Y-152763D01*
X156234D01*
G01X163690D02*
X169149Y-135263D01*
X174608Y-152763D01*
G01X172642Y-146638D02*
X165655D01*
G01X253482Y-90263D02*
Y-107763D01*
X262216D01*
G01X279279D02*
Y-96097D01*
G01Y-98138D02*
X278406Y-96972D01*
X277095Y-96388D01*
X275567Y-96097D01*
X274039Y-96680D01*
X272729Y-97846D01*
X271855Y-99596D01*
X271419Y-101930D01*
X271855Y-104263D01*
X272729Y-106013D01*
X274039Y-107180D01*
X275567Y-107763D01*
X277095Y-107471D01*
X278406Y-106597D01*
X279279Y-105430D01*
G01X288264Y-113013D02*
X289574Y-113596D01*
X291321Y-113013D01*
X292412Y-111847D01*
X293286Y-110388D01*
X294595Y-105722D01*
X297434Y-96097D01*
G01X290447D02*
X294595Y-105722D01*
G01X307074Y-99888D02*
X314061D01*
X313406Y-97846D01*
X312314Y-96680D01*
X310786Y-96097D01*
X309257Y-96388D01*
X307947Y-97263D01*
X307074Y-99305D01*
X306637Y-101055D01*
Y-102805D01*
X307074Y-104555D01*
X308166Y-106305D01*
X309476Y-107471D01*
X311004Y-107763D01*
X312532Y-107180D01*
X314061Y-105430D01*
G01X324792Y-107763D02*
Y-96097D01*
G01Y-98430D02*
X325884Y-97263D01*
X326976Y-96388D01*
X328504Y-96097D01*
X329595Y-96388D01*
X330906Y-97263D01*
G01X342074Y-105722D02*
X343166Y-106888D01*
X344694Y-107763D01*
X346004D01*
X347314Y-107180D01*
X348187Y-106305D01*
X348624Y-105139D01*
X348406Y-103388D01*
X347532Y-102513D01*
X343602Y-100763D01*
X342729Y-98721D01*
X343166Y-97263D01*
X344039Y-96388D01*
X345349Y-96097D01*
X346659Y-96388D01*
X347969Y-97263D01*
G01X266599Y-135263D02*
Y-152763D01*
G01X261577Y-135263D02*
X271621D01*
G01X278422Y-152763D02*
Y-135263D01*
X284099Y-149846D01*
X289776Y-135263D01*
Y-152763D01*
G01X296140D02*
X301599Y-135263D01*
X307058Y-152763D01*
G01X305092Y-146638D02*
X298105D01*
G01X314514Y-150430D02*
X316261Y-151888D01*
X318226Y-152763D01*
X319972D01*
X321719Y-151888D01*
X323029Y-150430D01*
X323684Y-148388D01*
X323247Y-146347D01*
X322156Y-144596D01*
X320191Y-143430D01*
X317571Y-142846D01*
X316042Y-141680D01*
X315387Y-139638D01*
X315824Y-137596D01*
X316916Y-136138D01*
X318444Y-135263D01*
X319972D01*
X321501Y-135846D01*
X322811Y-137305D01*
G01X331796Y-152763D02*
Y-135263D01*
G01X340092D02*
X331796Y-146055D01*
G01X341402Y-152763D02*
X335507Y-141097D01*
G01X404346Y-107763D02*
Y-90263D01*
X408712D01*
X410459Y-91138D01*
X411769Y-92305D01*
X412861Y-94054D01*
X413734Y-96097D01*
X413952Y-99013D01*
X413734Y-101930D01*
X412861Y-103972D01*
X411769Y-105722D01*
X410459Y-106888D01*
X408712Y-107763D01*
X404346D01*
G01X423374Y-99888D02*
X430361D01*
X429706Y-97846D01*
X428614Y-96680D01*
X427086Y-96097D01*
X425557Y-96388D01*
X424247Y-97263D01*
X423374Y-99305D01*
X422937Y-101055D01*
Y-102805D01*
X423374Y-104555D01*
X424466Y-106305D01*
X425776Y-107471D01*
X427304Y-107763D01*
X428832Y-107180D01*
X430361Y-105430D01*
G01X440874Y-105722D02*
X441966Y-106888D01*
X443494Y-107763D01*
X444804D01*
X446114Y-107180D01*
X446987Y-106305D01*
X447424Y-105139D01*
X447206Y-103388D01*
X446332Y-102513D01*
X442402Y-100763D01*
X441529Y-98721D01*
X441966Y-97263D01*
X442839Y-96388D01*
X444149Y-96097D01*
X445459Y-96388D01*
X446769Y-97263D01*
G01X461649Y-96097D02*
Y-107763D01*
G01Y-91430D02*
X461212Y-91138D01*
Y-90555D01*
X461649Y-90263D01*
X462086Y-90555D01*
Y-91138D01*
X461649Y-91430D01*
G01X476092Y-112138D02*
X477621Y-113305D01*
X479367Y-113596D01*
X480895Y-113305D01*
X482206Y-111847D01*
X483079Y-109805D01*
Y-96097D01*
G01Y-98430D02*
X482206Y-97263D01*
X480895Y-96388D01*
X479367Y-96097D01*
X477621Y-96680D01*
X476529Y-97846D01*
X475655Y-99888D01*
X475219Y-101930D01*
X475437Y-103680D01*
X476311Y-105722D01*
X477621Y-107180D01*
X479367Y-107763D01*
X480677Y-107471D01*
X482206Y-106305D01*
X483079Y-105139D01*
G01X492937Y-107763D02*
Y-96097D01*
G01Y-99013D02*
X493811Y-97555D01*
X495121Y-96388D01*
X496867Y-96097D01*
X498395Y-96388D01*
X499706Y-97555D01*
X500361Y-99596D01*
Y-107763D01*
G01X510874Y-99888D02*
X517861D01*
X517206Y-97846D01*
X516114Y-96680D01*
X514586Y-96097D01*
X513057Y-96388D01*
X511747Y-97263D01*
X510874Y-99305D01*
X510437Y-101055D01*
Y-102805D01*
X510874Y-104555D01*
X511966Y-106305D01*
X513276Y-107471D01*
X514804Y-107763D01*
X516332Y-107180D01*
X517861Y-105430D01*
G01X528592Y-107763D02*
Y-96097D01*
G01Y-98430D02*
X529684Y-97263D01*
X530776Y-96388D01*
X532304Y-96097D01*
X533395Y-96388D01*
X534706Y-97263D01*
G01X429722Y-152763D02*
Y-135263D01*
X435399Y-149846D01*
X441076Y-135263D01*
Y-152763D01*
G01X452899D02*
X451152Y-152471D01*
X449624Y-151305D01*
X448314Y-149555D01*
X447440Y-147513D01*
X447004Y-145180D01*
Y-142846D01*
X447440Y-140513D01*
X448314Y-138471D01*
X449624Y-136722D01*
X451152Y-135555D01*
X452899Y-135263D01*
X454645Y-135555D01*
X456174Y-136722D01*
X457484Y-138471D01*
X458358Y-140513D01*
X458794Y-142846D01*
Y-145180D01*
X458358Y-147513D01*
X457484Y-149555D01*
X456174Y-151305D01*
X454645Y-152471D01*
X452899Y-152763D01*
G01X465814Y-150430D02*
X467561Y-151888D01*
X469526Y-152763D01*
X471272D01*
X473019Y-151888D01*
X474329Y-150430D01*
X474984Y-148388D01*
X474547Y-146347D01*
X473456Y-144596D01*
X471491Y-143430D01*
X468871Y-142846D01*
X467342Y-141680D01*
X466687Y-139638D01*
X467124Y-137596D01*
X468216Y-136138D01*
X469744Y-135263D01*
X471272D01*
X472801Y-135846D01*
X474111Y-137305D01*
G01X483314Y-150430D02*
X485061Y-151888D01*
X487026Y-152763D01*
X488772D01*
X490519Y-151888D01*
X491829Y-150430D01*
X492484Y-148388D01*
X492047Y-146347D01*
X490956Y-144596D01*
X488991Y-143430D01*
X486371Y-142846D01*
X484842Y-141680D01*
X484187Y-139638D01*
X484624Y-137596D01*
X485716Y-136138D01*
X487244Y-135263D01*
X488772D01*
X490301Y-135846D01*
X491611Y-137305D01*
G01X509766Y-152763D02*
X501032D01*
Y-135263D01*
X509766D01*
G01X506272Y-143721D02*
X501032D01*
G01X575349Y-152763D02*
Y-135263D01*
X572729Y-138763D01*
G01Y-152763D02*
X577969D01*
G01X588701Y-138180D02*
X590011Y-136430D01*
X591539Y-135555D01*
X593286Y-135263D01*
X595469Y-135846D01*
X596997Y-137305D01*
X597434Y-139054D01*
X597216Y-140805D01*
X596342Y-142263D01*
X591976Y-145180D01*
X590011Y-147221D01*
X588701Y-150139D01*
X588264Y-152763D01*
X597434D01*
G01X606419Y-153346D02*
X614279Y-135263D01*
G01X627849Y-152763D02*
Y-135263D01*
X625229Y-138763D01*
G01Y-152763D02*
X630469D01*
G01X645349D02*
Y-135263D01*
X642729Y-138763D01*
G01Y-152763D02*
X647969D01*
G01X658919Y-153346D02*
X666779Y-135263D01*
G01X676201Y-138180D02*
X677511Y-136430D01*
X679039Y-135555D01*
X680786Y-135263D01*
X682969Y-135846D01*
X684497Y-137305D01*
X684934Y-139054D01*
X684716Y-140805D01*
X683842Y-142263D01*
X679476Y-145180D01*
X677511Y-147221D01*
X676201Y-150139D01*
X675764Y-152763D01*
X684934D01*
G01X697849Y-135263D02*
X696102Y-135846D01*
X694792Y-137305D01*
X693919Y-139054D01*
X693264Y-141388D01*
X693046Y-144013D01*
X693264Y-146638D01*
X693919Y-148972D01*
X694792Y-150722D01*
X696102Y-152180D01*
X697849Y-152763D01*
X699595Y-152180D01*
X700906Y-150722D01*
X701779Y-148972D01*
X702434Y-146638D01*
X702652Y-144013D01*
X702434Y-141388D01*
X701779Y-139054D01*
X700906Y-137305D01*
X699595Y-135846D01*
X697849Y-135263D01*
G01X715349Y-152763D02*
Y-135263D01*
X712729Y-138763D01*
G01Y-152763D02*
X717969D01*
G01X728046Y-150139D02*
X729355Y-151597D01*
X730884Y-152471D01*
X732849Y-152763D01*
X734814Y-152180D01*
X736342Y-151013D01*
X737434Y-148972D01*
X737652Y-146638D01*
X737216Y-144305D01*
X736124Y-142846D01*
X734595Y-141680D01*
X733067Y-141388D01*
X731539Y-141680D01*
X729574Y-142846D01*
X730229Y-135263D01*
X736124D01*
G01X623046Y-107763D02*
Y-90263D01*
X627412D01*
X629159Y-91138D01*
X630469Y-92305D01*
X631561Y-94054D01*
X632434Y-96097D01*
X632652Y-99013D01*
X632434Y-101930D01*
X631561Y-103972D01*
X630469Y-105722D01*
X629159Y-106888D01*
X627412Y-107763D01*
X623046D01*
G01X649279D02*
Y-96097D01*
G01Y-98138D02*
X648406Y-96972D01*
X647095Y-96388D01*
X645567Y-96097D01*
X644039Y-96680D01*
X642729Y-97846D01*
X641855Y-99596D01*
X641419Y-101930D01*
X641855Y-104263D01*
X642729Y-106013D01*
X644039Y-107180D01*
X645567Y-107763D01*
X647095Y-107471D01*
X648406Y-106597D01*
X649279Y-105430D01*
G01X662849Y-90263D02*
Y-107763D01*
G01X659792Y-96097D02*
X665906D01*
G01X677074Y-99888D02*
X684061D01*
X683406Y-97846D01*
X682314Y-96680D01*
X680786Y-96097D01*
X679257Y-96388D01*
X677947Y-97263D01*
X677074Y-99305D01*
X676637Y-101055D01*
Y-102805D01*
X677074Y-104555D01*
X678166Y-106305D01*
X679476Y-107471D01*
X681004Y-107763D01*
X682532Y-107180D01*
X684061Y-105430D01*
G54D78*
X117000Y1452000D03*
G54D69*
X136235Y618504D03*
Y620469D03*
Y622439D03*
Y624409D03*
Y626374D03*
Y628344D03*
Y630314D03*
Y632284D03*
Y634249D03*
Y636219D03*
Y638189D03*
Y640154D03*
X102835D03*
Y638189D03*
Y636219D03*
Y634249D03*
Y632284D03*
Y630314D03*
Y628344D03*
Y626374D03*
Y624409D03*
Y622439D03*
Y620469D03*
Y618504D03*
G54D79*
X161417Y1773425D03*
M02*
